(kicad_pcb
	(version 20260206)
	(generator "pcbnew")
	(generator_version "10.0")
	(general
		(thickness 1.6)
		(legacy_teardrops no)
	)
	(paper "A4")
	(title_block
		(title "v1-chassis-manager — T6M_CM_d_v01_1031_1645.brd")
		(comment 1 "Open CloudServer (Microsoft) / footprints 1983-1992 of 2512")
	)
	(layers
		(0 "F.Cu" signal "TOP")
		(4 "In1.Cu" signal "GND1")
		(6 "In2.Cu" signal "IN1")
		(8 "In3.Cu" signal "VCC1")
		(10 "In4.Cu" signal "VCC2")
		(12 "In5.Cu" signal "GND2")
		(14 "In6.Cu" signal "IN2")
		(16 "In7.Cu" signal "IN3")
		(18 "In8.Cu" signal "GND3")
		(2 "B.Cu" signal "BOTTOM")
		(9 "F.Adhes" user "F.Adhesive")
		(11 "B.Adhes" user "B.Adhesive")
		(13 "F.Paste" user "Package Geometry/Pastemask Top")
		(15 "B.Paste" user "Package Geometry/Pastemask Bottom")
		(5 "F.SilkS" user "Ref Des/Silkscreen Top")
		(7 "B.SilkS" user "Ref Des/Silkscreen Bottom")
		(1 "F.Mask" user "Board Geometry/Soldermask Top")
		(3 "B.Mask" user "Board Geometry/Soldermask Bottom")
		(17 "Dwgs.User" user "User.Drawings")
		(19 "Cmts.User" user "User.Comments")
		(21 "Eco1.User" user "User.Eco1")
		(23 "Eco2.User" user "User.Eco2")
		(25 "Edge.Cuts" user "Board Geometry/Outline")
		(27 "Margin" user)
		(31 "F.CrtYd" user "Package Geometry/Place Bound Top")
		(29 "B.CrtYd" user "Package Geometry/Place Bound Bottom")
		(35 "F.Fab" user "Ref Des/Assembly Top")
		(33 "B.Fab" user "Ref Des/Assembly Bottom")
	)
	(footprint ""
		(layer "B.Cu")
		(at 90.81262 -177.070512)
		(property "Reference" "R698"
			(at 24.902414 20.083272 0)
			(unlocked yes)
			(layer "B.SilkS")
			(effects
				(font
					(size 0.7874 0.5842)
					(thickness 0.1524)
				)
				(justify left mirror)
			)
		)
		(property "Value" ""
			(at 0 0 0)
			(layer "B.Fab")
			(effects
				(font
					(size 1.27 1.27)
				)
				(justify mirror)
			)
		)
		(duplicate_pad_numbers_are_jumpers no)
		(fp_line
			(start -0.7874 -0.4064)
			(end -0.7874 0.4064)
			(stroke
				(width 0.1524)
				(type default)
			)
			(layer "B.SilkS")
		)
		(fp_line
			(start -0.7874 0.4064)
			(end 0.7874 0.4064)
			(stroke
				(width 0.1524)
				(type default)
			)
			(layer "B.SilkS")
		)
		(fp_line
			(start 0.7874 -0.4064)
			(end -0.7874 -0.4064)
			(stroke
				(width 0.1524)
				(type default)
			)
			(layer "B.SilkS")
		)
		(fp_line
			(start 0.7874 0.4064)
			(end 0.7874 -0.4064)
			(stroke
				(width 0.1524)
				(type default)
			)
			(layer "B.SilkS")
		)
		(fp_poly
			(pts
				(xy 0.508 0.2794) (xy 0.508 0.2286) (xy 0.635 0.2286) (xy 0.635 -0.254) (xy 0.5334 -0.254) (xy 0.5334 -0.2794)
				(xy -0.5334 -0.2794) (xy -0.5334 -0.254) (xy -0.635 -0.254) (xy -0.635 0.254) (xy -0.5334 0.254)
				(xy -0.5334 0.2794)
			)
			(stroke
				(width 0)
				(type default)
			)
			(fill no)
			(layer "B.CrtYd")
		)
		(pad "1" smd rect
			(at -0.40005 0 180)
			(size 0.4572 0.508)
			(layers "B.Cu" "B.Mask" "B.Paste")
			(net "T3_NODE2_EN")
		)
		(pad "2" smd rect
			(at 0.40005 0 180)
			(size 0.4572 0.508)
			(layers "B.Cu" "B.Mask" "B.Paste")
			(net "P5V_NODE1")
		)
	)
	(footprint ""
		(layer "B.Cu")
		(at 138.236452 -151.28875 90)
		(property "Reference" "C874"
			(at 1.03378 3.353562 270)
			(unlocked yes)
			(layer "B.SilkS")
			(effects
				(font
					(size 0.7874 0.5842)
					(thickness 0.1524)
				)
				(justify left mirror)
			)
		)
		(property "Value" ""
			(at 0 0 90)
			(layer "B.Fab")
			(effects
				(font
					(size 1.27 1.27)
				)
				(justify mirror)
			)
		)
		(duplicate_pad_numbers_are_jumpers no)
		(fp_line
			(start 0.7874 -0.4064)
			(end -0.7874 -0.4064)
			(stroke
				(width 0.1524)
				(type default)
			)
			(layer "B.SilkS")
		)
		(fp_line
			(start -0.7874 -0.4064)
			(end -0.7874 0.4064)
			(stroke
				(width 0.1524)
				(type default)
			)
			(layer "B.SilkS")
		)
		(fp_line
			(start 0 0.381)
			(end 0 -0.381)
			(stroke
				(width 0.1524)
				(type default)
			)
			(layer "B.SilkS")
		)
		(fp_line
			(start 0.7874 0.4064)
			(end 0.7874 -0.4064)
			(stroke
				(width 0.1524)
				(type default)
			)
			(layer "B.SilkS")
		)
		(fp_line
			(start -0.7874 0.4064)
			(end 0.7874 0.4064)
			(stroke
				(width 0.1524)
				(type default)
			)
			(layer "B.SilkS")
		)
		(fp_poly
			(pts
				(xy 0.5334 0.254) (xy 0.635 0.254) (xy 0.635 0.2286) (xy 0.635 -0.254) (xy 0.5334 -0.254) (xy 0.5334 -0.2794)
				(xy -0.5334 -0.2794) (xy -0.5334 -0.254) (xy -0.635 -0.254) (xy -0.635 0.254) (xy -0.5334 0.254)
				(xy -0.5334 0.2794) (xy 0.508 0.2794) (xy 0.5334 0.2794)
			)
			(stroke
				(width 0)
				(type default)
			)
			(fill no)
			(layer "B.CrtYd")
		)
		(pad "1" smd rect
			(at -0.40005 0 270)
			(size 0.4572 0.508)
			(layers "B.Cu" "B.Mask" "B.Paste")
			(net "P1V0_NODE1")
		)
		(pad "2" smd rect
			(at 0.40005 0 270)
			(size 0.4572 0.508)
			(layers "B.Cu" "B.Mask" "B.Paste")
			(net "GND")
		)
	)
	(footprint ""
		(layer "B.Cu")
		(at 37.591746 -97.067878 -90)
		(property "Reference" "R126"
			(at -0.97155 0.021844 270)
			(unlocked yes)
			(layer "B.SilkS")
			(effects
				(font
					(size 0.7874 0.5842)
					(thickness 0.1524)
				)
				(justify left mirror)
			)
		)
		(property "Value" ""
			(at 0 0 90)
			(layer "B.Fab")
			(effects
				(font
					(size 1.27 1.27)
				)
				(justify mirror)
			)
		)
		(duplicate_pad_numbers_are_jumpers no)
		(fp_line
			(start -0.7874 0.4064)
			(end 0.7874 0.4064)
			(stroke
				(width 0.1524)
				(type default)
			)
			(layer "B.SilkS")
		)
		(fp_line
			(start 0.7874 0.4064)
			(end 0.7874 -0.4064)
			(stroke
				(width 0.1524)
				(type default)
			)
			(layer "B.SilkS")
		)
		(fp_line
			(start -0.7874 -0.4064)
			(end -0.7874 0.4064)
			(stroke
				(width 0.1524)
				(type default)
			)
			(layer "B.SilkS")
		)
		(fp_line
			(start 0.7874 -0.4064)
			(end -0.7874 -0.4064)
			(stroke
				(width 0.1524)
				(type default)
			)
			(layer "B.SilkS")
		)
		(fp_poly
			(pts
				(xy 0.508 0.2794) (xy 0.508 0.2286) (xy 0.635 0.2286) (xy 0.635 -0.254) (xy 0.5334 -0.254) (xy 0.5334 -0.2794)
				(xy -0.5334 -0.2794) (xy -0.5334 -0.254) (xy -0.635 -0.254) (xy -0.635 0.254) (xy -0.5334 0.254)
				(xy -0.5334 0.2794)
			)
			(stroke
				(width 0)
				(type default)
			)
			(fill no)
			(layer "B.CrtYd")
		)
		(pad "1" smd rect
			(at -0.40005 0 90)
			(size 0.4572 0.508)
			(layers "B.Cu" "B.Mask" "B.Paste")
			(net "P3V3_NODE1")
		)
		(pad "2" smd rect
			(at 0.40005 0 90)
			(size 0.4572 0.508)
			(layers "B.Cu" "B.Mask" "B.Paste")
			(net "SMB_MUX_CPU_ICS_NODE1_CLK")
		)
	)
	(footprint ""
		(layer "B.Cu")
		(at 119.49176 -185.205624 90)
		(property "Reference" "R872"
			(at 3.957828 0.26797 270)
			(unlocked yes)
			(layer "B.SilkS")
			(effects
				(font
					(size 0.7874 0.5842)
					(thickness 0.1524)
				)
				(justify left mirror)
			)
		)
		(property "Value" ""
			(at 0 0 90)
			(layer "B.Fab")
			(effects
				(font
					(size 1.27 1.27)
				)
				(justify mirror)
			)
		)
		(duplicate_pad_numbers_are_jumpers no)
		(fp_line
			(start 0.7874 -0.4064)
			(end -0.7874 -0.4064)
			(stroke
				(width 0.1524)
				(type default)
			)
			(layer "B.SilkS")
		)
		(fp_line
			(start -0.7874 -0.4064)
			(end -0.7874 0.4064)
			(stroke
				(width 0.1524)
				(type default)
			)
			(layer "B.SilkS")
		)
		(fp_line
			(start 0.7874 0.4064)
			(end 0.7874 -0.4064)
			(stroke
				(width 0.1524)
				(type default)
			)
			(layer "B.SilkS")
		)
		(fp_line
			(start -0.7874 0.4064)
			(end 0.7874 0.4064)
			(stroke
				(width 0.1524)
				(type default)
			)
			(layer "B.SilkS")
		)
		(fp_poly
			(pts
				(xy 0.508 0.2794) (xy 0.508 0.2286) (xy 0.635 0.2286) (xy 0.635 -0.254) (xy 0.5334 -0.254) (xy 0.5334 -0.2794)
				(xy -0.5334 -0.2794) (xy -0.5334 -0.254) (xy -0.635 -0.254) (xy -0.635 0.254) (xy -0.5334 0.254)
				(xy -0.5334 0.2794)
			)
			(stroke
				(width 0)
				(type default)
			)
			(fill no)
			(layer "B.CrtYd")
		)
		(pad "1" smd rect
			(at -0.40005 0 270)
			(size 0.4572 0.508)
			(layers "B.Cu" "B.Mask" "B.Paste")
			(net "T7_NODE1_EN")
		)
		(pad "2" smd rect
			(at 0.40005 0 270)
			(size 0.4572 0.508)
			(layers "B.Cu" "B.Mask" "B.Paste")
			(net "T7_NODE1_EN_R")
		)
	)
	(footprint ""
		(layer "B.Cu")
		(at 47.766732 -94.40037 90)
		(property "Reference" "R123"
			(at -4.703318 -4.33197 270)
			(unlocked yes)
			(layer "B.SilkS")
			(effects
				(font
					(size 0.7874 0.5842)
					(thickness 0.1524)
				)
				(justify left mirror)
			)
		)
		(property "Value" ""
			(at 0 0 90)
			(layer "B.Fab")
			(effects
				(font
					(size 1.27 1.27)
				)
				(justify mirror)
			)
		)
		(duplicate_pad_numbers_are_jumpers no)
		(fp_line
			(start 0.7874 -0.4064)
			(end -0.7874 -0.4064)
			(stroke
				(width 0.1524)
				(type default)
			)
			(layer "B.SilkS")
		)
		(fp_line
			(start -0.7874 -0.4064)
			(end -0.7874 0.4064)
			(stroke
				(width 0.1524)
				(type default)
			)
			(layer "B.SilkS")
		)
		(fp_line
			(start 0.7874 0.4064)
			(end 0.7874 -0.4064)
			(stroke
				(width 0.1524)
				(type default)
			)
			(layer "B.SilkS")
		)
		(fp_line
			(start -0.7874 0.4064)
			(end 0.7874 0.4064)
			(stroke
				(width 0.1524)
				(type default)
			)
			(layer "B.SilkS")
		)
		(fp_poly
			(pts
				(xy 0.508 0.2794) (xy 0.508 0.2286) (xy 0.635 0.2286) (xy 0.635 -0.254) (xy 0.5334 -0.254) (xy 0.5334 -0.2794)
				(xy -0.5334 -0.2794) (xy -0.5334 -0.254) (xy -0.635 -0.254) (xy -0.635 0.254) (xy -0.5334 0.254)
				(xy -0.5334 0.2794)
			)
			(stroke
				(width 0)
				(type default)
			)
			(fill no)
			(layer "B.CrtYd")
		)
		(pad "1" smd rect
			(at -0.40005 0 270)
			(size 0.4572 0.508)
			(layers "B.Cu" "B.Mask" "B.Paste")
			(net "SMB_CPU_NODE1_XDP_DAT_R")
		)
		(pad "2" smd rect
			(at 0.40005 0 270)
			(size 0.4572 0.508)
			(layers "B.Cu" "B.Mask" "B.Paste")
			(net "SMB_CPU_NODE1_XDP_DAT")
		)
	)
	(footprint ""
		(layer "B.Cu")
		(at 90.81262 -170.974512)
		(property "Reference" "R709"
			(at 24.902414 20.163028 0)
			(unlocked yes)
			(layer "B.SilkS")
			(effects
				(font
					(size 0.7874 0.5842)
					(thickness 0.1524)
				)
				(justify left mirror)
			)
		)
		(property "Value" ""
			(at 0 0 0)
			(layer "B.Fab")
			(effects
				(font
					(size 1.27 1.27)
				)
				(justify mirror)
			)
		)
		(duplicate_pad_numbers_are_jumpers no)
		(fp_line
			(start -0.7874 -0.4064)
			(end -0.7874 0.4064)
			(stroke
				(width 0.1524)
				(type default)
			)
			(layer "B.SilkS")
		)
		(fp_line
			(start -0.7874 0.4064)
			(end 0.7874 0.4064)
			(stroke
				(width 0.1524)
				(type default)
			)
			(layer "B.SilkS")
		)
		(fp_line
			(start 0.7874 -0.4064)
			(end -0.7874 -0.4064)
			(stroke
				(width 0.1524)
				(type default)
			)
			(layer "B.SilkS")
		)
		(fp_line
			(start 0.7874 0.4064)
			(end 0.7874 -0.4064)
			(stroke
				(width 0.1524)
				(type default)
			)
			(layer "B.SilkS")
		)
		(fp_poly
			(pts
				(xy 0.508 0.2794) (xy 0.508 0.2286) (xy 0.635 0.2286) (xy 0.635 -0.254) (xy 0.5334 -0.254) (xy 0.5334 -0.2794)
				(xy -0.5334 -0.2794) (xy -0.5334 -0.254) (xy -0.635 -0.254) (xy -0.635 0.254) (xy -0.5334 0.254)
				(xy -0.5334 0.2794)
			)
			(stroke
				(width 0)
				(type default)
			)
			(fill no)
			(layer "B.CrtYd")
		)
		(pad "1" smd rect
			(at -0.40005 0 180)
			(size 0.4572 0.508)
			(layers "B.Cu" "B.Mask" "B.Paste")
			(net "T4_NODE4_EN")
		)
		(pad "2" smd rect
			(at 0.40005 0 180)
			(size 0.4572 0.508)
			(layers "B.Cu" "B.Mask" "B.Paste")
			(net "P5V_NODE1")
		)
	)
	(footprint ""
		(layer "B.Cu")
		(at 147.305014 -72.667622 180)
		(property "Reference" "C348"
			(at -4.93522 0.651764 0)
			(unlocked yes)
			(layer "B.SilkS")
			(effects
				(font
					(size 0.7874 0.5842)
					(thickness 0.1524)
				)
				(justify left mirror)
			)
		)
		(property "Value" ""
			(at 0 0 0)
			(layer "B.Fab")
			(effects
				(font
					(size 1.27 1.27)
				)
				(justify mirror)
			)
		)
		(duplicate_pad_numbers_are_jumpers no)
		(fp_line
			(start 0.7874 0.4064)
			(end 0.7874 -0.4064)
			(stroke
				(width 0.1524)
				(type default)
			)
			(layer "B.SilkS")
		)
		(fp_line
			(start 0.7874 -0.4064)
			(end -0.7874 -0.4064)
			(stroke
				(width 0.1524)
				(type default)
			)
			(layer "B.SilkS")
		)
		(fp_line
			(start 0 0.381)
			(end 0 -0.381)
			(stroke
				(width 0.1524)
				(type default)
			)
			(layer "B.SilkS")
		)
		(fp_line
			(start -0.7874 0.4064)
			(end 0.7874 0.4064)
			(stroke
				(width 0.1524)
				(type default)
			)
			(layer "B.SilkS")
		)
		(fp_line
			(start -0.7874 -0.4064)
			(end -0.7874 0.4064)
			(stroke
				(width 0.1524)
				(type default)
			)
			(layer "B.SilkS")
		)
		(fp_poly
			(pts
				(xy 0.5334 0.254) (xy 0.635 0.254) (xy 0.635 0.2286) (xy 0.635 -0.254) (xy 0.5334 -0.254) (xy 0.5334 -0.2794)
				(xy -0.5334 -0.2794) (xy -0.5334 -0.254) (xy -0.635 -0.254) (xy -0.635 0.254) (xy -0.5334 0.254)
				(xy -0.5334 0.2794) (xy 0.508 0.2794) (xy 0.5334 0.2794)
			)
			(stroke
				(width 0)
				(type default)
			)
			(fill no)
			(layer "B.CrtYd")
		)
		(pad "1" smd rect
			(at -0.40005 0)
			(size 0.4572 0.508)
			(layers "B.Cu" "B.Mask" "B.Paste")
			(net "P1V8_SATA_AVDD_NODE1")
		)
		(pad "2" smd rect
			(at 0.40005 0)
			(size 0.4572 0.508)
			(layers "B.Cu" "B.Mask" "B.Paste")
			(net "GND")
		)
	)
	(footprint ""
		(layer "B.Cu")
		(at 159.62376 -187.872624 90)
		(property "Reference" "R830"
			(at 4.565396 -4.067556 270)
			(unlocked yes)
			(layer "B.SilkS")
			(effects
				(font
					(size 0.7874 0.5842)
					(thickness 0.1524)
				)
				(justify left mirror)
			)
		)
		(property "Value" ""
			(at 0 0 90)
			(layer "B.Fab")
			(effects
				(font
					(size 1.27 1.27)
				)
				(justify mirror)
			)
		)
		(duplicate_pad_numbers_are_jumpers no)
		(fp_line
			(start 0.7874 -0.4064)
			(end -0.7874 -0.4064)
			(stroke
				(width 0.1524)
				(type default)
			)
			(layer "B.SilkS")
		)
		(fp_line
			(start -0.7874 -0.4064)
			(end -0.7874 0.4064)
			(stroke
				(width 0.1524)
				(type default)
			)
			(layer "B.SilkS")
		)
		(fp_line
			(start 0.7874 0.4064)
			(end 0.7874 -0.4064)
			(stroke
				(width 0.1524)
				(type default)
			)
			(layer "B.SilkS")
		)
		(fp_line
			(start -0.7874 0.4064)
			(end 0.7874 0.4064)
			(stroke
				(width 0.1524)
				(type default)
			)
			(layer "B.SilkS")
		)
		(fp_poly
			(pts
				(xy 0.508 0.2794) (xy 0.508 0.2286) (xy 0.635 0.2286) (xy 0.635 -0.254) (xy 0.5334 -0.254) (xy 0.5334 -0.2794)
				(xy -0.5334 -0.2794) (xy -0.5334 -0.254) (xy -0.635 -0.254) (xy -0.635 0.254) (xy -0.5334 0.254)
				(xy -0.5334 0.2794)
			)
			(stroke
				(width 0)
				(type default)
			)
			(fill no)
			(layer "B.CrtYd")
		)
		(pad "1" smd rect
			(at -0.40005 0 270)
			(size 0.4572 0.508)
			(layers "B.Cu" "B.Mask" "B.Paste")
			(net "FAN6_TACH")
		)
		(pad "2" smd rect
			(at 0.40005 0 270)
			(size 0.4572 0.508)
			(layers "B.Cu" "B.Mask" "B.Paste")
			(net "FAN6_TACH_R")
		)
	)
	(footprint ""
		(layer "B.Cu")
		(at 102.557072 -171.750482)
		(property "Reference" "R799"
			(at 8.71601 1.026668 0)
			(unlocked yes)
			(layer "B.SilkS")
			(effects
				(font
					(size 0.7874 0.5842)
					(thickness 0.1524)
				)
				(justify left mirror)
			)
		)
		(property "Value" ""
			(at 0 0 0)
			(layer "B.Fab")
			(effects
				(font
					(size 1.27 1.27)
				)
				(justify mirror)
			)
		)
		(duplicate_pad_numbers_are_jumpers no)
		(fp_line
			(start -0.7874 -0.4064)
			(end -0.7874 0.4064)
			(stroke
				(width 0.1524)
				(type default)
			)
			(layer "B.SilkS")
		)
		(fp_line
			(start -0.7874 0.4064)
			(end 0.7874 0.4064)
			(stroke
				(width 0.1524)
				(type default)
			)
			(layer "B.SilkS")
		)
		(fp_line
			(start 0.7874 -0.4064)
			(end -0.7874 -0.4064)
			(stroke
				(width 0.1524)
				(type default)
			)
			(layer "B.SilkS")
		)
		(fp_line
			(start 0.7874 0.4064)
			(end 0.7874 -0.4064)
			(stroke
				(width 0.1524)
				(type default)
			)
			(layer "B.SilkS")
		)
		(fp_poly
			(pts
				(xy 0.508 0.2794) (xy 0.508 0.2286) (xy 0.635 0.2286) (xy 0.635 -0.254) (xy 0.5334 -0.254) (xy 0.5334 -0.2794)
				(xy -0.5334 -0.2794) (xy -0.5334 -0.254) (xy -0.635 -0.254) (xy -0.635 0.254) (xy -0.5334 0.254)
				(xy -0.5334 0.2794)
			)
			(stroke
				(width 0)
				(type default)
			)
			(fill no)
			(layer "B.CrtYd")
		)
		(pad "1" smd rect
			(at -0.40005 0 180)
			(size 0.4572 0.508)
			(layers "B.Cu" "B.Mask" "B.Paste")
			(net "P3V3_NODE1")
		)
		(pad "2" smd rect
			(at 0.40005 0 180)
			(size 0.4572 0.508)
			(layers "B.Cu" "B.Mask" "B.Paste")
			(net "FAN_PWM_BUF")
		)
	)
	(footprint ""
		(layer "B.Cu")
		(at 94.451932 -172.124624)
		(property "Reference" "R701"
			(at 1.83642 14.389608 0)
			(unlocked yes)
			(layer "B.SilkS")
			(effects
				(font
					(size 0.7874 0.5842)
					(thickness 0.1524)
				)
				(justify left mirror)
			)
		)
		(property "Value" ""
			(at 0 0 0)
			(layer "B.Fab")
			(effects
				(font
					(size 1.27 1.27)
				)
				(justify mirror)
			)
		)
		(duplicate_pad_numbers_are_jumpers no)
		(fp_line
			(start -0.7874 -0.4064)
			(end -0.7874 0.4064)
			(stroke
				(width 0.1524)
				(type default)
			)
			(layer "B.SilkS")
		)
		(fp_line
			(start -0.7874 0.4064)
			(end 0.7874 0.4064)
			(stroke
				(width 0.1524)
				(type default)
			)
			(layer "B.SilkS")
		)
		(fp_line
			(start 0.7874 -0.4064)
			(end -0.7874 -0.4064)
			(stroke
				(width 0.1524)
				(type default)
			)
			(layer "B.SilkS")
		)
		(fp_line
			(start 0.7874 0.4064)
			(end 0.7874 -0.4064)
			(stroke
				(width 0.1524)
				(type default)
			)
			(layer "B.SilkS")
		)
		(fp_poly
			(pts
				(xy 0.508 0.2794) (xy 0.508 0.2286) (xy 0.635 0.2286) (xy 0.635 -0.254) (xy 0.5334 -0.254) (xy 0.5334 -0.2794)
				(xy -0.5334 -0.2794) (xy -0.5334 -0.254) (xy -0.635 -0.254) (xy -0.635 0.254) (xy -0.5334 0.254)
				(xy -0.5334 0.2794)
			)
			(stroke
				(width 0)
				(type default)
			)
			(fill no)
			(layer "B.CrtYd")
		)
		(pad "1" smd rect
			(at -0.40005 0 180)
			(size 0.4572 0.508)
			(layers "B.Cu" "B.Mask" "B.Paste")
			(net "P3V3_NODE1")
		)
		(pad "2" smd rect
			(at 0.40005 0 180)
			(size 0.4572 0.508)
			(layers "B.Cu" "B.Mask" "B.Paste")
			(net "N21701263")
		)
	)
)
